# T6G (Grand Teton) — schematic netlist excerpt (pin names and nets, part order shuffled) for the footprints in the layout excerpt that follows; sources: Cadence DE-HDL packaged netlist, KiCad conversion of 04192023_DAF0TMB3IC0_F0TG_MB_C_brd_V02_OCP.brd

R3592  Q_RES  33.2 1% CHIP  pkg 0402LF  page 251 : A = SMB_INA230_3V3AUX_SCL ; B = SMB_INA230_5_3V3AUX_SCL_R
R3110  Q_RES  0 5% CHIP  pkg 0402LF  page 248 : A = SMB_1_BMC_GPU_SDA ; B = SMB_1_BMC_GPU_R_SDA

(kicad_pcb
	(version 20260206)
	(generator "pcbnew")
	(generator_version "10.0")
	(general
		(thickness 1.6)
		(legacy_teardrops no)
	)
	(paper "A4")
	(title_block
		(title "04192023_DAF0TMB3IC0_F0TG_MB_C_brd_V02_OCP.brd")
		(comment 1 "Grand Teton / footprints 2177-2178 of 8354")
	)
	(layers
		(0 "F.Cu" signal "TOP")
		(4 "In1.Cu" signal "GND")
		(6 "In2.Cu" signal "IN1")
		(8 "In3.Cu" signal "GND1")
		(10 "In4.Cu" signal "IN2")
		(12 "In5.Cu" signal "GND2")
		(14 "In6.Cu" signal "IN3")
		(16 "In7.Cu" signal "GND3")
		(18 "In8.Cu" signal "VCC")
		(20 "In9.Cu" signal "VCC1")
		(22 "In10.Cu" signal "GND4")
		(24 "In11.Cu" signal "IN4")
		(26 "In12.Cu" signal "GND5")
		(28 "In13.Cu" signal "IN5")
		(30 "In14.Cu" signal "GND6")
		(32 "In15.Cu" signal "IN6")
		(34 "In16.Cu" signal "GND7")
		(2 "B.Cu" signal "BOTTOM")
		(9 "F.Adhes" user "F.Adhesive")
		(11 "B.Adhes" user "B.Adhesive")
		(13 "F.Paste" user "Package Geometry/Pastemask Top")
		(15 "B.Paste" user "Package Geometry/Pastemask Bottom")
		(5 "F.SilkS" user "Ref Des/Silkscreen Top")
		(7 "B.SilkS" user "Ref Des/Silkscreen Bottom")
		(1 "F.Mask" user "Board Geometry/Soldermask Top")
		(3 "B.Mask" user "Board Geometry/Soldermask Bottom")
		(17 "Dwgs.User" user "User.Drawings")
		(19 "Cmts.User" user "User.Comments")
		(21 "Eco1.User" user "User.Eco1")
		(23 "Eco2.User" user "User.Eco2")
		(25 "Edge.Cuts" user "Board Geometry/Outline")
		(27 "Margin" user)
		(31 "F.CrtYd" user "Package Geometry/Place Bound Top")
		(29 "B.CrtYd" user "Package Geometry/Place Bound Bottom")
		(35 "F.Fab" user "Ref Des/Assembly Top")
		(33 "B.Fab" user "Ref Des/Assembly Bottom")
	)
	(footprint ""
		(layer "F.Cu")
		(at 35.15868 -432.056794 180)
		(property "Reference" "R3110"
			(at 0 0 180)
			(layer "F.SilkS")
			(hide yes)
			(effects
				(font
					(size 1.27 1.27)
				)
			)
		)
		(property "Value" ""
			(at 0 0 180)
			(layer "F.Fab")
			(effects
				(font
					(size 1.27 1.27)
				)
			)
		)
		(duplicate_pad_numbers_are_jumpers no)
		(fp_line
			(start 0.7874 0.4064)
			(end -0.7874 0.4064)
			(stroke
				(width 0.1524)
				(type default)
			)
			(layer "F.SilkS")
		)
		(fp_line
			(start 0.7874 -0.4064)
			(end 0.7874 0.4064)
			(stroke
				(width 0.1524)
				(type default)
			)
			(layer "F.SilkS")
		)
		(fp_line
			(start -0.7874 0.4064)
			(end -0.7874 -0.4064)
			(stroke
				(width 0.1524)
				(type default)
			)
			(layer "F.SilkS")
		)
		(fp_line
			(start -0.7874 -0.4064)
			(end 0.7874 -0.4064)
			(stroke
				(width 0.1524)
				(type default)
			)
			(layer "F.SilkS")
		)
		(fp_line
			(start 0.67945 0.3048)
			(end 0.120396 0.3048)
			(stroke
				(width 0.1)
				(type default)
			)
			(layer "F.Fab")
		)
		(fp_line
			(start 0.67945 -0.3048)
			(end 0.67945 0.3048)
			(stroke
				(width 0.1)
				(type default)
			)
			(layer "F.Fab")
		)
		(fp_line
			(start 0.12065 -0.2794)
			(end 0.12065 -0.3048)
			(stroke
				(width 0.1)
				(type default)
			)
			(layer "F.Fab")
		)
		(fp_line
			(start 0.12065 -0.3048)
			(end 0.67945 -0.3048)
			(stroke
				(width 0.1)
				(type default)
			)
			(layer "F.Fab")
		)
		(fp_line
			(start 0.120396 0.3048)
			(end 0.120396 0.2794)
			(stroke
				(width 0.1)
				(type default)
			)
			(layer "F.Fab")
		)
		(fp_line
			(start 0.120396 0.2794)
			(end -0.12065 0.2794)
			(stroke
				(width 0.1)
				(type default)
			)
			(layer "F.Fab")
		)
		(fp_line
			(start -0.12065 0.3048)
			(end -0.67945 0.3048)
			(stroke
				(width 0.1)
				(type default)
			)
			(layer "F.Fab")
		)
		(fp_line
			(start -0.12065 0.2794)
			(end -0.12065 0.3048)
			(stroke
				(width 0.1)
				(type default)
			)
			(layer "F.Fab")
		)
		(fp_line
			(start -0.12065 -0.2794)
			(end 0.12065 -0.2794)
			(stroke
				(width 0.1)
				(type default)
			)
			(layer "F.Fab")
		)
		(fp_line
			(start -0.12065 -0.305054)
			(end -0.12065 -0.2794)
			(stroke
				(width 0.1)
				(type default)
			)
			(layer "F.Fab")
		)
		(fp_line
			(start -0.67945 0.3048)
			(end -0.67945 -0.305054)
			(stroke
				(width 0.1)
				(type default)
			)
			(layer "F.Fab")
		)
		(fp_line
			(start -0.67945 -0.305054)
			(end -0.12065 -0.305054)
			(stroke
				(width 0.1)
				(type default)
			)
			(layer "F.Fab")
		)
		(pad "1" smd circle
			(at -0.40005 0 180)
			(size 0 0)
			(layers "F.Cu" "F.Mask" "F.Paste")
			(net "SMB_1_BMC_GPU_SDA")
		)
		(pad "2" smd circle
			(at 0.40005 0 180)
			(size 0 0)
			(layers "F.Cu" "F.Mask" "F.Paste")
			(net "SMB_1_BMC_GPU_R_SDA")
		)
	)
	(footprint ""
		(layer "F.Cu")
		(at 215.956134 -34.508948 180)
		(property "Reference" "R3592"
			(at 0 0 180)
			(layer "F.SilkS")
			(hide yes)
			(effects
				(font
					(size 1.27 1.27)
				)
			)
		)
		(property "Value" ""
			(at 0 0 180)
			(layer "F.Fab")
			(effects
				(font
					(size 1.27 1.27)
				)
			)
		)
		(duplicate_pad_numbers_are_jumpers no)
		(fp_line
			(start 0.7874 0.4064)
			(end -0.7874 0.4064)
			(stroke
				(width 0.1524)
				(type default)
			)
			(layer "F.SilkS")
		)
		(fp_line
			(start 0.7874 -0.4064)
			(end 0.7874 0.4064)
			(stroke
				(width 0.1524)
				(type default)
			)
			(layer "F.SilkS")
		)
		(fp_line
			(start -0.7874 0.4064)
			(end -0.7874 -0.4064)
			(stroke
				(width 0.1524)
				(type default)
			)
			(layer "F.SilkS")
		)
		(fp_line
			(start -0.7874 -0.4064)
			(end 0.7874 -0.4064)
			(stroke
				(width 0.1524)
				(type default)
			)
			(layer "F.SilkS")
		)
		(fp_line
			(start 0.67945 0.3048)
			(end 0.120396 0.3048)
			(stroke
				(width 0.1)
				(type default)
			)
			(layer "F.Fab")
		)
		(fp_line
			(start 0.67945 -0.3048)
			(end 0.67945 0.3048)
			(stroke
				(width 0.1)
				(type default)
			)
			(layer "F.Fab")
		)
		(fp_line
			(start 0.12065 -0.2794)
			(end 0.12065 -0.3048)
			(stroke
				(width 0.1)
				(type default)
			)
			(layer "F.Fab")
		)
		(fp_line
			(start 0.12065 -0.3048)
			(end 0.67945 -0.3048)
			(stroke
				(width 0.1)
				(type default)
			)
			(layer "F.Fab")
		)
		(fp_line
			(start 0.120396 0.3048)
			(end 0.120396 0.2794)
			(stroke
				(width 0.1)
				(type default)
			)
			(layer "F.Fab")
		)
		(fp_line
			(start 0.120396 0.2794)
			(end -0.12065 0.2794)
			(stroke
				(width 0.1)
				(type default)
			)
			(layer "F.Fab")
		)
		(fp_line
			(start -0.12065 0.3048)
			(end -0.67945 0.3048)
			(stroke
				(width 0.1)
				(type default)
			)
			(layer "F.Fab")
		)
		(fp_line
			(start -0.12065 0.2794)
			(end -0.12065 0.3048)
			(stroke
				(width 0.1)
				(type default)
			)
			(layer "F.Fab")
		)
		(fp_line
			(start -0.12065 -0.2794)
			(end 0.12065 -0.2794)
			(stroke
				(width 0.1)
				(type default)
			)
			(layer "F.Fab")
		)
		(fp_line
			(start -0.12065 -0.305054)
			(end -0.12065 -0.2794)
			(stroke
				(width 0.1)
				(type default)
			)
			(layer "F.Fab")
		)
		(fp_line
			(start -0.67945 0.3048)
			(end -0.67945 -0.305054)
			(stroke
				(width 0.1)
				(type default)
			)
			(layer "F.Fab")
		)
		(fp_line
			(start -0.67945 -0.305054)
			(end -0.12065 -0.305054)
			(stroke
				(width 0.1)
				(type default)
			)
			(layer "F.Fab")
		)
		(pad "1" smd circle
			(at -0.40005 0 180)
			(size 0 0)
			(layers "F.Cu" "F.Mask" "F.Paste")
			(net "SMB_INA230_3V3AUX_SCL")
		)
		(pad "2" smd circle
			(at 0.40005 0 180)
			(size 0 0)
			(layers "F.Cu" "F.Mask" "F.Paste")
			(net "SMB_INA230_5_3V3AUX_SCL_R")
		)
	)
)
